(kicad_pcb
	(version 20260206)
	(generator "pcbnew")
	(generator_version "10.0")
	(general
		(thickness 1.6)
		(legacy_teardrops no)
	)
	(paper "A4")
	(title_block
		(title "03242023_DA0F0TMBIJ0_F0T_Motherboard_J_brd_V01_OCP.brd")
		(comment 1 "Grand Teton / footprints 1673-1679 of 6105")
	)
	(layers
		(0 "F.Cu" signal "TOP")
		(4 "In1.Cu" signal "GND")
		(6 "In2.Cu" signal "IN1")
		(8 "In3.Cu" signal "GND1")
		(10 "In4.Cu" signal "IN2")
		(12 "In5.Cu" signal "GND2")
		(14 "In6.Cu" signal "IN3")
		(16 "In7.Cu" signal "GND3")
		(18 "In8.Cu" signal "VCC")
		(20 "In9.Cu" signal "VCC1")
		(22 "In10.Cu" signal "GND4")
		(24 "In11.Cu" signal "IN4")
		(26 "In12.Cu" signal "GND5")
		(28 "In13.Cu" signal "IN5")
		(30 "In14.Cu" signal "GND6")
		(32 "In15.Cu" signal "IN6")
		(34 "In16.Cu" signal "GND7")
		(2 "B.Cu" signal "BOTTOM")
		(9 "F.Adhes" user "F.Adhesive")
		(11 "B.Adhes" user "B.Adhesive")
		(13 "F.Paste" user "Package Geometry/Pastemask Top")
		(15 "B.Paste" user "Package Geometry/Pastemask Bottom")
		(5 "F.SilkS" user "Ref Des/Silkscreen Top")
		(7 "B.SilkS" user "Ref Des/Silkscreen Bottom")
		(1 "F.Mask" user "Board Geometry/Soldermask Top")
		(3 "B.Mask" user "Board Geometry/Soldermask Bottom")
		(17 "Dwgs.User" user "User.Drawings")
		(19 "Cmts.User" user "User.Comments")
		(21 "Eco1.User" user "User.Eco1")
		(23 "Eco2.User" user "User.Eco2")
		(25 "Edge.Cuts" user "Board Geometry/Outline")
		(27 "Margin" user)
		(31 "F.CrtYd" user "Package Geometry/Place Bound Top")
		(29 "B.CrtYd" user "Package Geometry/Place Bound Bottom")
		(35 "F.Fab" user "Ref Des/Assembly Top")
		(33 "B.Fab" user "Ref Des/Assembly Bottom")
	)
	(footprint ""
		(layer "F.Cu")
		(at 449.650612 -23.594314 180)
		(property "Reference" "PC2085"
			(at 0 0 180)
			(layer "F.SilkS")
			(hide yes)
			(effects
				(font
					(size 1.27 1.27)
				)
			)
		)
		(property "Value" ""
			(at 0 0 180)
			(layer "F.Fab")
			(effects
				(font
					(size 1.27 1.27)
				)
			)
		)
		(duplicate_pad_numbers_are_jumpers no)
		(fp_line
			(start 0.7874 0.4064)
			(end -0.7874 0.4064)
			(stroke
				(width 0.1524)
				(type default)
			)
			(layer "F.SilkS")
		)
		(fp_line
			(start 0.7874 -0.4064)
			(end 0.7874 0.4064)
			(stroke
				(width 0.1524)
				(type default)
			)
			(layer "F.SilkS")
		)
		(fp_line
			(start -0.7874 0.4064)
			(end -0.7874 -0.4064)
			(stroke
				(width 0.1524)
				(type default)
			)
			(layer "F.SilkS")
		)
		(fp_line
			(start -0.7874 -0.4064)
			(end 0.7874 -0.4064)
			(stroke
				(width 0.1524)
				(type default)
			)
			(layer "F.SilkS")
		)
		(fp_line
			(start 0.67945 0.3048)
			(end 0.120396 0.3048)
			(stroke
				(width 0.1)
				(type default)
			)
			(layer "F.Fab")
		)
		(fp_line
			(start 0.67945 -0.3048)
			(end 0.67945 0.3048)
			(stroke
				(width 0.1)
				(type default)
			)
			(layer "F.Fab")
		)
		(fp_line
			(start 0.12065 -0.2794)
			(end 0.12065 -0.3048)
			(stroke
				(width 0.1)
				(type default)
			)
			(layer "F.Fab")
		)
		(fp_line
			(start 0.12065 -0.3048)
			(end 0.67945 -0.3048)
			(stroke
				(width 0.1)
				(type default)
			)
			(layer "F.Fab")
		)
		(fp_line
			(start 0.120396 0.3048)
			(end 0.120396 0.2794)
			(stroke
				(width 0.1)
				(type default)
			)
			(layer "F.Fab")
		)
		(fp_line
			(start 0.120396 0.2794)
			(end -0.12065 0.2794)
			(stroke
				(width 0.1)
				(type default)
			)
			(layer "F.Fab")
		)
		(fp_line
			(start -0.12065 0.3048)
			(end -0.67945 0.3048)
			(stroke
				(width 0.1)
				(type default)
			)
			(layer "F.Fab")
		)
		(fp_line
			(start -0.12065 0.2794)
			(end -0.12065 0.3048)
			(stroke
				(width 0.1)
				(type default)
			)
			(layer "F.Fab")
		)
		(fp_line
			(start -0.12065 -0.2794)
			(end 0.12065 -0.2794)
			(stroke
				(width 0.1)
				(type default)
			)
			(layer "F.Fab")
		)
		(fp_line
			(start -0.12065 -0.305054)
			(end -0.12065 -0.2794)
			(stroke
				(width 0.1)
				(type default)
			)
			(layer "F.Fab")
		)
		(fp_line
			(start -0.67945 0.3048)
			(end -0.67945 -0.305054)
			(stroke
				(width 0.1)
				(type default)
			)
			(layer "F.Fab")
		)
		(fp_line
			(start -0.67945 -0.305054)
			(end -0.12065 -0.305054)
			(stroke
				(width 0.1)
				(type default)
			)
			(layer "F.Fab")
		)
		(pad "1" smd circle
			(at -0.40005 0 180)
			(size 0 0)
			(layers "F.Cu" "F.Mask" "F.Paste")
			(net "P12V_OCP_VCC_1")
		)
		(pad "2" smd circle
			(at 0.40005 0 180)
			(size 0 0)
			(layers "F.Cu" "F.Mask" "F.Paste")
			(net "GND")
		)
	)
	(footprint ""
		(layer "F.Cu")
		(at 60.207398 -402.371052 -90)
		(property "Reference" "C718"
			(at 0 0 270)
			(layer "F.SilkS")
			(hide yes)
			(effects
				(font
					(size 1.27 1.27)
				)
			)
		)
		(property "Value" ""
			(at 0 0 270)
			(layer "F.Fab")
			(effects
				(font
					(size 1.27 1.27)
				)
			)
		)
		(duplicate_pad_numbers_are_jumpers no)
		(fp_line
			(start -0.299974 0.150114)
			(end -0.299974 -0.150114)
			(stroke
				(width 0.1)
				(type default)
			)
			(layer "F.Fab")
		)
		(fp_line
			(start 0.299974 0.150114)
			(end -0.299974 0.150114)
			(stroke
				(width 0.1)
				(type default)
			)
			(layer "F.Fab")
		)
		(fp_line
			(start -0.299974 -0.150114)
			(end 0.299974 -0.150114)
			(stroke
				(width 0.1)
				(type default)
			)
			(layer "F.Fab")
		)
		(fp_line
			(start 0.299974 -0.150114)
			(end 0.299974 0.150114)
			(stroke
				(width 0.1)
				(type default)
			)
			(layer "F.Fab")
		)
		(pad "1" smd rect
			(at -0.2667 0 270)
			(size 0.3048 0.381)
			(layers "F.Cu" "F.Mask" "F.Paste")
			(net "P5E_CPU1_PE0_TX_C_DN<11>")
		)
		(pad "2" smd rect
			(at 0.2667 0 270)
			(size 0.3048 0.381)
			(layers "F.Cu" "F.Mask" "F.Paste")
			(net "P5E_CPU1_PE0_TX_DN<11>")
		)
	)
	(footprint ""
		(layer "F.Cu")
		(at 95.125286 -427.776386 90)
		(property "Reference" "R3502"
			(at 0 0 90)
			(layer "F.SilkS")
			(hide yes)
			(effects
				(font
					(size 1.27 1.27)
				)
			)
		)
		(property "Value" ""
			(at 0 0 90)
			(layer "F.Fab")
			(effects
				(font
					(size 1.27 1.27)
				)
			)
		)
		(duplicate_pad_numbers_are_jumpers no)
		(fp_line
			(start 0.7874 -0.4064)
			(end 0.7874 0.4064)
			(stroke
				(width 0.1524)
				(type default)
			)
			(layer "F.SilkS")
		)
		(fp_line
			(start -0.7874 -0.4064)
			(end 0.7874 -0.4064)
			(stroke
				(width 0.1524)
				(type default)
			)
			(layer "F.SilkS")
		)
		(fp_line
			(start 0.7874 0.4064)
			(end -0.7874 0.4064)
			(stroke
				(width 0.1524)
				(type default)
			)
			(layer "F.SilkS")
		)
		(fp_line
			(start -0.7874 0.4064)
			(end -0.7874 -0.4064)
			(stroke
				(width 0.1524)
				(type default)
			)
			(layer "F.SilkS")
		)
		(fp_line
			(start -0.12065 -0.305054)
			(end -0.12065 -0.2794)
			(stroke
				(width 0.1)
				(type default)
			)
			(layer "F.Fab")
		)
		(fp_line
			(start -0.67945 -0.305054)
			(end -0.12065 -0.305054)
			(stroke
				(width 0.1)
				(type default)
			)
			(layer "F.Fab")
		)
		(fp_line
			(start 0.67945 -0.3048)
			(end 0.67945 0.3048)
			(stroke
				(width 0.1)
				(type default)
			)
			(layer "F.Fab")
		)
		(fp_line
			(start 0.12065 -0.3048)
			(end 0.67945 -0.3048)
			(stroke
				(width 0.1)
				(type default)
			)
			(layer "F.Fab")
		)
		(fp_line
			(start 0.12065 -0.2794)
			(end 0.12065 -0.3048)
			(stroke
				(width 0.1)
				(type default)
			)
			(layer "F.Fab")
		)
		(fp_line
			(start -0.12065 -0.2794)
			(end 0.12065 -0.2794)
			(stroke
				(width 0.1)
				(type default)
			)
			(layer "F.Fab")
		)
		(fp_line
			(start 0.120396 0.2794)
			(end -0.12065 0.2794)
			(stroke
				(width 0.1)
				(type default)
			)
			(layer "F.Fab")
		)
		(fp_line
			(start -0.12065 0.2794)
			(end -0.12065 0.3048)
			(stroke
				(width 0.1)
				(type default)
			)
			(layer "F.Fab")
		)
		(fp_line
			(start 0.67945 0.3048)
			(end 0.120396 0.3048)
			(stroke
				(width 0.1)
				(type default)
			)
			(layer "F.Fab")
		)
		(fp_line
			(start 0.120396 0.3048)
			(end 0.120396 0.2794)
			(stroke
				(width 0.1)
				(type default)
			)
			(layer "F.Fab")
		)
		(fp_line
			(start -0.12065 0.3048)
			(end -0.67945 0.3048)
			(stroke
				(width 0.1)
				(type default)
			)
			(layer "F.Fab")
		)
		(fp_line
			(start -0.67945 0.3048)
			(end -0.67945 -0.305054)
			(stroke
				(width 0.1)
				(type default)
			)
			(layer "F.Fab")
		)
		(pad "1" smd circle
			(at -0.40005 0 90)
			(size 0 0)
			(layers "F.Cu" "F.Mask" "F.Paste")
			(net "GPU_FPGA_EROT_FATALERR_N")
		)
		(pad "2" smd circle
			(at 0.40005 0 90)
			(size 0 0)
			(layers "F.Cu" "F.Mask" "F.Paste")
			(net "GND")
		)
	)
	(footprint ""
		(layer "F.Cu")
		(at 342.059768 -408.517344 -90)
		(property "Reference" "C926"
			(at 0 0 270)
			(layer "F.SilkS")
			(hide yes)
			(effects
				(font
					(size 1.27 1.27)
				)
			)
		)
		(property "Value" ""
			(at 0 0 270)
			(layer "F.Fab")
			(effects
				(font
					(size 1.27 1.27)
				)
			)
		)
		(duplicate_pad_numbers_are_jumpers no)
		(fp_line
			(start -0.299974 0.150114)
			(end -0.299974 -0.150114)
			(stroke
				(width 0.1)
				(type default)
			)
			(layer "F.Fab")
		)
		(fp_line
			(start 0.299974 0.150114)
			(end -0.299974 0.150114)
			(stroke
				(width 0.1)
				(type default)
			)
			(layer "F.Fab")
		)
		(fp_line
			(start -0.299974 -0.150114)
			(end 0.299974 -0.150114)
			(stroke
				(width 0.1)
				(type default)
			)
			(layer "F.Fab")
		)
		(fp_line
			(start 0.299974 -0.150114)
			(end 0.299974 0.150114)
			(stroke
				(width 0.1)
				(type default)
			)
			(layer "F.Fab")
		)
		(pad "1" smd rect
			(at -0.2667 0 270)
			(size 0.3048 0.381)
			(layers "F.Cu" "F.Mask" "F.Paste")
			(net "P5E_CPU0_PE0_TX_C_DN<3>")
		)
		(pad "2" smd rect
			(at 0.2667 0 270)
			(size 0.3048 0.381)
			(layers "F.Cu" "F.Mask" "F.Paste")
			(net "P5E_CPU0_PE0_TX_DN<3>")
		)
	)
	(footprint ""
		(layer "F.Cu")
		(at 168.449498 -353.36353 -90)
		(property "Reference" "PC1242_P1_1"
			(at 0 0 270)
			(layer "F.SilkS")
			(hide yes)
			(effects
				(font
					(size 1.27 1.27)
				)
			)
		)
		(property "Value" ""
			(at 0 0 270)
			(layer "F.Fab")
			(effects
				(font
					(size 1.27 1.27)
				)
			)
		)
		(duplicate_pad_numbers_are_jumpers no)
		(fp_line
			(start -0.7874 0.4064)
			(end -0.7874 -0.4064)
			(stroke
				(width 0.1524)
				(type default)
			)
			(layer "F.SilkS")
		)
		(fp_line
			(start 0.7874 0.4064)
			(end -0.7874 0.4064)
			(stroke
				(width 0.1524)
				(type default)
			)
			(layer "F.SilkS")
		)
		(fp_line
			(start -0.7874 -0.4064)
			(end 0.7874 -0.4064)
			(stroke
				(width 0.1524)
				(type default)
			)
			(layer "F.SilkS")
		)
		(fp_line
			(start 0.7874 -0.4064)
			(end 0.7874 0.4064)
			(stroke
				(width 0.1524)
				(type default)
			)
			(layer "F.SilkS")
		)
		(fp_line
			(start -0.67945 0.3048)
			(end -0.67945 -0.305054)
			(stroke
				(width 0.1)
				(type default)
			)
			(layer "F.Fab")
		)
		(fp_line
			(start -0.12065 0.3048)
			(end -0.67945 0.3048)
			(stroke
				(width 0.1)
				(type default)
			)
			(layer "F.Fab")
		)
		(fp_line
			(start 0.120396 0.3048)
			(end 0.120396 0.2794)
			(stroke
				(width 0.1)
				(type default)
			)
			(layer "F.Fab")
		)
		(fp_line
			(start 0.67945 0.3048)
			(end 0.120396 0.3048)
			(stroke
				(width 0.1)
				(type default)
			)
			(layer "F.Fab")
		)
		(fp_line
			(start -0.12065 0.2794)
			(end -0.12065 0.3048)
			(stroke
				(width 0.1)
				(type default)
			)
			(layer "F.Fab")
		)
		(fp_line
			(start 0.120396 0.2794)
			(end -0.12065 0.2794)
			(stroke
				(width 0.1)
				(type default)
			)
			(layer "F.Fab")
		)
		(fp_line
			(start -0.12065 -0.2794)
			(end 0.12065 -0.2794)
			(stroke
				(width 0.1)
				(type default)
			)
			(layer "F.Fab")
		)
		(fp_line
			(start 0.12065 -0.2794)
			(end 0.12065 -0.3048)
			(stroke
				(width 0.1)
				(type default)
			)
			(layer "F.Fab")
		)
		(fp_line
			(start 0.12065 -0.3048)
			(end 0.67945 -0.3048)
			(stroke
				(width 0.1)
				(type default)
			)
			(layer "F.Fab")
		)
		(fp_line
			(start 0.67945 -0.3048)
			(end 0.67945 0.3048)
			(stroke
				(width 0.1)
				(type default)
			)
			(layer "F.Fab")
		)
		(fp_line
			(start -0.67945 -0.305054)
			(end -0.12065 -0.305054)
			(stroke
				(width 0.1)
				(type default)
			)
			(layer "F.Fab")
		)
		(fp_line
			(start -0.12065 -0.305054)
			(end -0.12065 -0.2794)
			(stroke
				(width 0.1)
				(type default)
			)
			(layer "F.Fab")
		)
		(pad "1" smd circle
			(at -0.40005 0 270)
			(size 0 0)
			(layers "F.Cu" "F.Mask" "F.Paste")
			(net "PVCCFA_EHV_FIVRA_CPU1_PVCC1")
		)
		(pad "2" smd circle
			(at 0.40005 0 270)
			(size 0 0)
			(layers "F.Cu" "F.Mask" "F.Paste")
			(net "GND")
		)
	)
	(footprint ""
		(layer "F.Cu")
		(at 193.60388 -107.495848)
		(property "Reference" "R1492"
			(at 0 0 0)
			(layer "F.SilkS")
			(hide yes)
			(effects
				(font
					(size 1.27 1.27)
				)
			)
		)
		(property "Value" ""
			(at 0 0 0)
			(layer "F.Fab")
			(effects
				(font
					(size 1.27 1.27)
				)
			)
		)
		(duplicate_pad_numbers_are_jumpers no)
		(fp_line
			(start -0.7874 -0.4064)
			(end 0.7874 -0.4064)
			(stroke
				(width 0.1524)
				(type default)
			)
			(layer "F.SilkS")
		)
		(fp_line
			(start -0.7874 0.4064)
			(end -0.7874 -0.4064)
			(stroke
				(width 0.1524)
				(type default)
			)
			(layer "F.SilkS")
		)
		(fp_line
			(start 0.7874 -0.4064)
			(end 0.7874 0.4064)
			(stroke
				(width 0.1524)
				(type default)
			)
			(layer "F.SilkS")
		)
		(fp_line
			(start 0.7874 0.4064)
			(end -0.7874 0.4064)
			(stroke
				(width 0.1524)
				(type default)
			)
			(layer "F.SilkS")
		)
		(fp_line
			(start -0.67945 -0.305054)
			(end -0.12065 -0.305054)
			(stroke
				(width 0.1)
				(type default)
			)
			(layer "F.Fab")
		)
		(fp_line
			(start -0.67945 0.3048)
			(end -0.67945 -0.305054)
			(stroke
				(width 0.1)
				(type default)
			)
			(layer "F.Fab")
		)
		(fp_line
			(start -0.12065 -0.305054)
			(end -0.12065 -0.2794)
			(stroke
				(width 0.1)
				(type default)
			)
			(layer "F.Fab")
		)
		(fp_line
			(start -0.12065 -0.2794)
			(end 0.12065 -0.2794)
			(stroke
				(width 0.1)
				(type default)
			)
			(layer "F.Fab")
		)
		(fp_line
			(start -0.12065 0.2794)
			(end -0.12065 0.3048)
			(stroke
				(width 0.1)
				(type default)
			)
			(layer "F.Fab")
		)
		(fp_line
			(start -0.12065 0.3048)
			(end -0.67945 0.3048)
			(stroke
				(width 0.1)
				(type default)
			)
			(layer "F.Fab")
		)
		(fp_line
			(start 0.120396 0.2794)
			(end -0.12065 0.2794)
			(stroke
				(width 0.1)
				(type default)
			)
			(layer "F.Fab")
		)
		(fp_line
			(start 0.120396 0.3048)
			(end 0.120396 0.2794)
			(stroke
				(width 0.1)
				(type default)
			)
			(layer "F.Fab")
		)
		(fp_line
			(start 0.12065 -0.3048)
			(end 0.67945 -0.3048)
			(stroke
				(width 0.1)
				(type default)
			)
			(layer "F.Fab")
		)
		(fp_line
			(start 0.12065 -0.2794)
			(end 0.12065 -0.3048)
			(stroke
				(width 0.1)
				(type default)
			)
			(layer "F.Fab")
		)
		(fp_line
			(start 0.67945 -0.3048)
			(end 0.67945 0.3048)
			(stroke
				(width 0.1)
				(type default)
			)
			(layer "F.Fab")
		)
		(fp_line
			(start 0.67945 0.3048)
			(end 0.120396 0.3048)
			(stroke
				(width 0.1)
				(type default)
			)
			(layer "F.Fab")
		)
		(pad "1" smd circle
			(at -0.40005 0)
			(size 0 0)
			(layers "F.Cu" "F.Mask" "F.Paste")
			(net "FM_DIS_PS_PWROK_DLY")
		)
		(pad "2" smd circle
			(at 0.40005 0)
			(size 0 0)
			(layers "F.Cu" "F.Mask" "F.Paste")
			(net "P3V3_AUX")
		)
	)
	(footprint ""
		(layer "F.Cu")
		(at 308.33314 -430.73701 -90)
		(property "Reference" "R4124"
			(at 0 0 270)
			(layer "F.SilkS")
			(hide yes)
			(effects
				(font
					(size 1.27 1.27)
				)
			)
		)
		(property "Value" ""
			(at 0 0 270)
			(layer "F.Fab")
			(effects
				(font
					(size 1.27 1.27)
				)
			)
		)
		(duplicate_pad_numbers_are_jumpers no)
		(fp_line
			(start -0.7874 0.4064)
			(end -0.7874 -0.4064)
			(stroke
				(width 0.1524)
				(type default)
			)
			(layer "F.SilkS")
		)
		(fp_line
			(start 0.7874 0.4064)
			(end -0.7874 0.4064)
			(stroke
				(width 0.1524)
				(type default)
			)
			(layer "F.SilkS")
		)
		(fp_line
			(start -0.7874 -0.4064)
			(end 0.7874 -0.4064)
			(stroke
				(width 0.1524)
				(type default)
			)
			(layer "F.SilkS")
		)
		(fp_line
			(start 0.7874 -0.4064)
			(end 0.7874 0.4064)
			(stroke
				(width 0.1524)
				(type default)
			)
			(layer "F.SilkS")
		)
		(fp_line
			(start -0.67945 0.3048)
			(end -0.67945 -0.305054)
			(stroke
				(width 0.1)
				(type default)
			)
			(layer "F.Fab")
		)
		(fp_line
			(start -0.12065 0.3048)
			(end -0.67945 0.3048)
			(stroke
				(width 0.1)
				(type default)
			)
			(layer "F.Fab")
		)
		(fp_line
			(start 0.120396 0.3048)
			(end 0.120396 0.2794)
			(stroke
				(width 0.1)
				(type default)
			)
			(layer "F.Fab")
		)
		(fp_line
			(start 0.67945 0.3048)
			(end 0.120396 0.3048)
			(stroke
				(width 0.1)
				(type default)
			)
			(layer "F.Fab")
		)
		(fp_line
			(start -0.12065 0.2794)
			(end -0.12065 0.3048)
			(stroke
				(width 0.1)
				(type default)
			)
			(layer "F.Fab")
		)
		(fp_line
			(start 0.120396 0.2794)
			(end -0.12065 0.2794)
			(stroke
				(width 0.1)
				(type default)
			)
			(layer "F.Fab")
		)
		(fp_line
			(start -0.12065 -0.2794)
			(end 0.12065 -0.2794)
			(stroke
				(width 0.1)
				(type default)
			)
			(layer "F.Fab")
		)
		(fp_line
			(start 0.12065 -0.2794)
			(end 0.12065 -0.3048)
			(stroke
				(width 0.1)
				(type default)
			)
			(layer "F.Fab")
		)
		(fp_line
			(start 0.12065 -0.3048)
			(end 0.67945 -0.3048)
			(stroke
				(width 0.1)
				(type default)
			)
			(layer "F.Fab")
		)
		(fp_line
			(start 0.67945 -0.3048)
			(end 0.67945 0.3048)
			(stroke
				(width 0.1)
				(type default)
			)
			(layer "F.Fab")
		)
		(fp_line
			(start -0.67945 -0.305054)
			(end -0.12065 -0.305054)
			(stroke
				(width 0.1)
				(type default)
			)
			(layer "F.Fab")
		)
		(fp_line
			(start -0.12065 -0.305054)
			(end -0.12065 -0.2794)
			(stroke
				(width 0.1)
				(type default)
			)
			(layer "F.Fab")
		)
		(pad "1" smd circle
			(at -0.40005 0 270)
			(size 0 0)
			(layers "F.Cu" "F.Mask" "F.Paste")
			(net "GPU_3V3IO_RSVD1_FFU")
		)
		(pad "2" smd circle
			(at 0.40005 0 270)
			(size 0 0)
			(layers "F.Cu" "F.Mask" "F.Paste")
			(net "GND")
		)
	)
)
